(kicad_pcb
	(version 20260206)
	(generator "pcbnew")
	(generator_version "10.0")
	(general
		(thickness 1.6)
		(legacy_teardrops no)
	)
	(paper "A4")
	(title_block
		(title "peb — Lightning_PEB_BRD.brd")
		(comment 1 "Lightning (Wiwynn / Facebook NVMe JBOF) / footprint 139 of 2563 (CN16), pads 1-76 of 166")
	)
	(layers
		(0 "F.Cu" signal "TOP")
		(4 "In1.Cu" signal "L2GND")
		(6 "In2.Cu" signal "L3")
		(8 "In3.Cu" signal "L4VCC")
		(10 "In4.Cu" signal "L5VCC")
		(12 "In5.Cu" signal "L6")
		(14 "In6.Cu" signal "L7GND")
		(2 "B.Cu" signal "BOTTOM")
		(9 "F.Adhes" user "F.Adhesive")
		(11 "B.Adhes" user "B.Adhesive")
		(13 "F.Paste" user "Package Geometry/Pastemask Top")
		(15 "B.Paste" user "Package Geometry/Pastemask Bottom")
		(5 "F.SilkS" user "Ref Des/Silkscreen Top")
		(7 "B.SilkS" user "Ref Des/Silkscreen Bottom")
		(1 "F.Mask" user "Board Geometry/Soldermask Top")
		(3 "B.Mask" user "Board Geometry/Soldermask Bottom")
		(17 "Dwgs.User" user "User.Drawings")
		(19 "Cmts.User" user "User.Comments")
		(21 "Eco1.User" user "User.Eco1")
		(23 "Eco2.User" user "User.Eco2")
		(25 "Edge.Cuts" user "Board Geometry/Outline")
		(27 "Margin" user)
		(31 "F.CrtYd" user "Package Geometry/Place Bound Top")
		(29 "B.CrtYd" user "Package Geometry/Place Bound Bottom")
		(35 "F.Fab" user "Ref Des/Assembly Top")
		(33 "B.Fab" user "Ref Des/Assembly Bottom")
	)
	(footprint ""
		(layer "F.Cu")
		(at 305.63439 -9.53008)
		(property "Reference" "CN16"
			(at 0 0 0)
			(layer "F.SilkS")
			(hide yes)
			(effects
				(font
					(size 1.27 1.27)
				)
			)
		)
		(property "Value" "MLX-CONN144-12R-3-GP-U2"
			(at -33.7693 -12.9032 0)
			(unlocked yes)
			(layer "F.Fab")
			(hide yes)
			(effects
				(font
					(size 1.016 1.016)
					(thickness 0.1524)
				)
			)
		)
		(property "Device Type" "PREFIT-144P-459383U2H519"
			(at -33.7693 -14.4272 0)
			(unlocked yes)
			(layer "F.Fab")
			(hide yes)
			(effects
				(font
					(size 1.016 1.016)
					(thickness 0.1524)
				)
			)
		)
		(duplicate_pad_numbers_are_jumpers no)
		(pad "AA1" thru_hole circle
			(at -19.500088 -4.400042)
			(size 0.7366 0.7366)
			(drill 0.369824)
			(layers "*.Cu" "*.Mask")
			(remove_unused_layers no)
			(net "PCIE_REFCLK_H0_P_R")
			(clearance 0.1778)
			(thermal_gap 0.1778)
		)
		(pad "AA2" thru_hole circle
			(at -18.750026 -2.999994)
			(size 0.7366 0.7366)
			(drill 0.369824)
			(layers "*.Cu" "*.Mask")
			(remove_unused_layers no)
			(net "PCIE_REFCLK_H0_N_R")
			(clearance 0.1778)
			(thermal_gap 0.1778)
		)
		(pad "AA3" thru_hole circle
			(at -17.999964 -3.700018)
			(size 0.7366 0.7366)
			(drill 0.369824)
			(layers "*.Cu" "*.Mask")
			(remove_unused_layers no)
			(net "GND")
			(clearance 0.1778)
			(thermal_gap 0.1778)
		)
		(pad "AA4" thru_hole circle
			(at -17.249902 -4.400042)
			(size 0.7366 0.7366)
			(drill 0.369824)
			(layers "*.Cu" "*.Mask")
			(remove_unused_layers no)
			(net "PCIE_RX_P0")
			(clearance 0.1778)
			(thermal_gap 0.1778)
		)
		(pad "AA5" thru_hole circle
			(at -16.500094 -2.999994)
			(size 0.7366 0.7366)
			(drill 0.369824)
			(layers "*.Cu" "*.Mask")
			(remove_unused_layers no)
			(net "PCIE_RX_N0")
			(clearance 0.1778)
			(thermal_gap 0.1778)
		)
		(pad "AA6" thru_hole circle
			(at -15.750032 -3.700018)
			(size 0.7366 0.7366)
			(drill 0.369824)
			(layers "*.Cu" "*.Mask")
			(remove_unused_layers no)
			(net "GND")
			(clearance 0.1778)
			(thermal_gap 0.1778)
		)
		(pad "AA7" thru_hole circle
			(at -14.99997 -4.400042)
			(size 0.7366 0.7366)
			(drill 0.369824)
			(layers "*.Cu" "*.Mask")
			(remove_unused_layers no)
			(net "PCIE_RX_P3")
			(clearance 0.1778)
			(thermal_gap 0.1778)
		)
		(pad "AA8" thru_hole circle
			(at -14.249908 -2.999994)
			(size 0.7366 0.7366)
			(drill 0.369824)
			(layers "*.Cu" "*.Mask")
			(remove_unused_layers no)
			(net "PCIE_RX_N3")
			(clearance 0.1778)
			(thermal_gap 0.1778)
		)
		(pad "AA9" thru_hole circle
			(at -13.5001 -3.700018)
			(size 0.7366 0.7366)
			(drill 0.369824)
			(layers "*.Cu" "*.Mask")
			(remove_unused_layers no)
			(net "GND")
			(clearance 0.1778)
			(thermal_gap 0.1778)
		)
		(pad "AB1" thru_hole circle
			(at -19.500088 -8.199882)
			(size 0.7366 0.7366)
			(drill 0.369824)
			(layers "*.Cu" "*.Mask")
			(remove_unused_layers no)
			(net "HOST5_RST_N_C")
			(clearance 0.1778)
			(thermal_gap 0.1778)
		)
		(pad "AB2" thru_hole circle
			(at -18.750026 -6.800088)
			(size 0.7366 0.7366)
			(drill 0.369824)
			(layers "*.Cu" "*.Mask")
			(remove_unused_layers no)
			(net "8644_SDA_R_5")
			(clearance 0.1778)
			(thermal_gap 0.1778)
		)
		(pad "AB3" thru_hole circle
			(at -17.999964 -7.500112)
			(size 0.7366 0.7366)
			(drill 0.369824)
			(layers "*.Cu" "*.Mask")
			(remove_unused_layers no)
			(net "GND")
			(clearance 0.1778)
			(thermal_gap 0.1778)
		)
		(pad "AB4" thru_hole circle
			(at -17.249902 -8.199882)
			(size 0.7366 0.7366)
			(drill 0.369824)
			(layers "*.Cu" "*.Mask")
			(remove_unused_layers no)
			(net "PCIE_RX_P1")
			(clearance 0.1778)
			(thermal_gap 0.1778)
		)
		(pad "AB5" thru_hole circle
			(at -16.500094 -6.800088)
			(size 0.7366 0.7366)
			(drill 0.369824)
			(layers "*.Cu" "*.Mask")
			(remove_unused_layers no)
			(net "PCIE_RX_N1")
			(clearance 0.1778)
			(thermal_gap 0.1778)
		)
		(pad "AB6" thru_hole circle
			(at -15.750032 -7.500112)
			(size 0.7366 0.7366)
			(drill 0.369824)
			(layers "*.Cu" "*.Mask")
			(remove_unused_layers no)
			(net "GND")
			(clearance 0.1778)
			(thermal_gap 0.1778)
		)
		(pad "AB7" thru_hole circle
			(at -14.99997 -8.199882)
			(size 0.7366 0.7366)
			(drill 0.369824)
			(layers "*.Cu" "*.Mask")
			(remove_unused_layers no)
			(net "PCIE_RX_P2")
			(clearance 0.1778)
			(thermal_gap 0.1778)
		)
		(pad "AB8" thru_hole circle
			(at -14.249908 -6.800088)
			(size 0.7366 0.7366)
			(drill 0.369824)
			(layers "*.Cu" "*.Mask")
			(remove_unused_layers no)
			(net "PCIE_RX_N2")
			(clearance 0.1778)
			(thermal_gap 0.1778)
		)
		(pad "AB9" thru_hole circle
			(at -13.5001 -7.500112)
			(size 0.7366 0.7366)
			(drill 0.369824)
			(layers "*.Cu" "*.Mask")
			(remove_unused_layers no)
			(net "GND")
			(clearance 0.1778)
			(thermal_gap 0.1778)
		)
		(pad "AC1" thru_hole circle
			(at -19.500088 -11.999976)
			(size 0.7366 0.7366)
			(drill 0.369824)
			(layers "*.Cu" "*.Mask")
			(remove_unused_layers no)
			(net "BMC_I2C11_MINI5_SCL")
			(clearance 0.1778)
			(thermal_gap 0.1778)
		)
		(pad "AC2" thru_hole circle
			(at -18.750026 -10.599928)
			(size 0.7366 0.7366)
			(drill 0.369824)
			(layers "*.Cu" "*.Mask")
			(remove_unused_layers no)
			(net "8644_CBL_PRSNT_R_5")
			(clearance 0.1778)
			(thermal_gap 0.1778)
		)
		(pad "AC3" thru_hole circle
			(at -17.999964 -11.299952)
			(size 0.7366 0.7366)
			(drill 0.369824)
			(layers "*.Cu" "*.Mask")
			(remove_unused_layers no)
			(net "GND")
			(clearance 0.1778)
			(thermal_gap 0.1778)
		)
		(pad "AC4" thru_hole circle
			(at -17.249902 -11.999976)
			(size 0.7366 0.7366)
			(drill 0.369824)
			(layers "*.Cu" "*.Mask")
			(remove_unused_layers no)
			(net "PCIE_TX_P0")
			(clearance 0.1778)
			(thermal_gap 0.1778)
		)
		(pad "AC5" thru_hole circle
			(at -16.500094 -10.599928)
			(size 0.7366 0.7366)
			(drill 0.369824)
			(layers "*.Cu" "*.Mask")
			(remove_unused_layers no)
			(net "PCIE_TX_N0")
			(clearance 0.1778)
			(thermal_gap 0.1778)
		)
		(pad "AC6" thru_hole circle
			(at -15.750032 -11.299952)
			(size 0.7366 0.7366)
			(drill 0.369824)
			(layers "*.Cu" "*.Mask")
			(remove_unused_layers no)
			(net "GND")
			(clearance 0.1778)
			(thermal_gap 0.1778)
		)
		(pad "AC7" thru_hole circle
			(at -14.99997 -11.999976)
			(size 0.7366 0.7366)
			(drill 0.369824)
			(layers "*.Cu" "*.Mask")
			(remove_unused_layers no)
			(net "PCIE_TX_P3")
			(clearance 0.1778)
			(thermal_gap 0.1778)
		)
		(pad "AC8" thru_hole circle
			(at -14.249908 -10.599928)
			(size 0.7366 0.7366)
			(drill 0.369824)
			(layers "*.Cu" "*.Mask")
			(remove_unused_layers no)
			(net "PCIE_TX_N3")
			(clearance 0.1778)
			(thermal_gap 0.1778)
		)
		(pad "AC9" thru_hole circle
			(at -13.5001 -11.299952)
			(size 0.7366 0.7366)
			(drill 0.369824)
			(layers "*.Cu" "*.Mask")
			(remove_unused_layers no)
			(net "GND")
			(clearance 0.1778)
			(thermal_gap 0.1778)
		)
		(pad "AD1" thru_hole circle
			(at -19.500088 -15.80007)
			(size 0.7366 0.7366)
			(drill 0.369824)
			(layers "*.Cu" "*.Mask")
			(remove_unused_layers no)
			(net "8644_USB_DN5")
			(clearance 0.1778)
			(thermal_gap 0.1778)
		)
		(pad "AD2" thru_hole circle
			(at -18.750026 -14.400022)
			(size 0.7366 0.7366)
			(drill 0.369824)
			(layers "*.Cu" "*.Mask")
			(remove_unused_layers no)
			(net "8644_USB_DP5")
			(clearance 0.1778)
			(thermal_gap 0.1778)
		)
		(pad "AD3" thru_hole circle
			(at -17.999964 -15.100046)
			(size 0.7366 0.7366)
			(drill 0.369824)
			(layers "*.Cu" "*.Mask")
			(remove_unused_layers no)
			(net "GND")
			(clearance 0.1778)
			(thermal_gap 0.1778)
		)
		(pad "AD4" thru_hole circle
			(at -17.249902 -15.80007)
			(size 0.7366 0.7366)
			(drill 0.369824)
			(layers "*.Cu" "*.Mask")
			(remove_unused_layers no)
			(net "PCIE_TX_P1")
			(clearance 0.1778)
			(thermal_gap 0.1778)
		)
		(pad "AD5" thru_hole circle
			(at -16.500094 -14.400022)
			(size 0.7366 0.7366)
			(drill 0.369824)
			(layers "*.Cu" "*.Mask")
			(remove_unused_layers no)
			(net "PCIE_TX_N1")
			(clearance 0.1778)
			(thermal_gap 0.1778)
		)
		(pad "AD6" thru_hole circle
			(at -15.750032 -15.100046)
			(size 0.7366 0.7366)
			(drill 0.369824)
			(layers "*.Cu" "*.Mask")
			(remove_unused_layers no)
			(net "GND")
			(clearance 0.1778)
			(thermal_gap 0.1778)
		)
		(pad "AD7" thru_hole circle
			(at -14.99997 -15.80007)
			(size 0.7366 0.7366)
			(drill 0.369824)
			(layers "*.Cu" "*.Mask")
			(remove_unused_layers no)
			(net "PCIE_TX_P2")
			(clearance 0.1778)
			(thermal_gap 0.1778)
		)
		(pad "AD8" thru_hole circle
			(at -14.249908 -14.400022)
			(size 0.7366 0.7366)
			(drill 0.369824)
			(layers "*.Cu" "*.Mask")
			(remove_unused_layers no)
			(net "PCIE_TX_N2")
			(clearance 0.1778)
			(thermal_gap 0.1778)
		)
		(pad "AD9" thru_hole circle
			(at -13.5001 -15.100046)
			(size 0.7366 0.7366)
			(drill 0.369824)
			(layers "*.Cu" "*.Mask")
			(remove_unused_layers no)
			(net "GND")
			(clearance 0.1778)
			(thermal_gap 0.1778)
		)
		(pad "BA1" thru_hole circle
			(at -8.50011 -4.400042)
			(size 0.7366 0.7366)
			(drill 0.369824)
			(layers "*.Cu" "*.Mask")
			(remove_unused_layers no)
			(net "CLK_P_6")
			(clearance 0.1778)
			(thermal_gap 0.1778)
		)
		(pad "BA2" thru_hole circle
			(at -7.750048 -2.999994)
			(size 0.7366 0.7366)
			(drill 0.369824)
			(layers "*.Cu" "*.Mask")
			(remove_unused_layers no)
			(net "CLK_N_6")
			(clearance 0.1778)
			(thermal_gap 0.1778)
		)
		(pad "BA3" thru_hole circle
			(at -6.999986 -3.700018)
			(size 0.7366 0.7366)
			(drill 0.369824)
			(layers "*.Cu" "*.Mask")
			(remove_unused_layers no)
			(net "GND")
			(clearance 0.1778)
			(thermal_gap 0.1778)
		)
		(pad "BA4" thru_hole circle
			(at -6.249924 -4.400042)
			(size 0.7366 0.7366)
			(drill 0.369824)
			(layers "*.Cu" "*.Mask")
			(remove_unused_layers no)
			(net "PCIE_RX_P4")
			(clearance 0.1778)
			(thermal_gap 0.1778)
		)
		(pad "BA5" thru_hole circle
			(at -5.500116 -2.999994)
			(size 0.7366 0.7366)
			(drill 0.369824)
			(layers "*.Cu" "*.Mask")
			(remove_unused_layers no)
			(net "PCIE_RX_N4")
			(clearance 0.1778)
			(thermal_gap 0.1778)
		)
		(pad "BA6" thru_hole circle
			(at -4.750054 -3.700018)
			(size 0.7366 0.7366)
			(drill 0.369824)
			(layers "*.Cu" "*.Mask")
			(remove_unused_layers no)
			(net "GND")
			(clearance 0.1778)
			(thermal_gap 0.1778)
		)
		(pad "BA7" thru_hole circle
			(at -3.999992 -4.400042)
			(size 0.7366 0.7366)
			(drill 0.369824)
			(layers "*.Cu" "*.Mask")
			(remove_unused_layers no)
			(net "PCIE_RX_P7")
			(clearance 0.1778)
			(thermal_gap 0.1778)
		)
		(pad "BA8" thru_hole circle
			(at -3.24993 -2.999994)
			(size 0.7366 0.7366)
			(drill 0.369824)
			(layers "*.Cu" "*.Mask")
			(remove_unused_layers no)
			(net "PCIE_RX_N7")
			(clearance 0.1778)
			(thermal_gap 0.1778)
		)
		(pad "BA9" thru_hole circle
			(at -2.500122 -3.700018)
			(size 0.7366 0.7366)
			(drill 0.369824)
			(layers "*.Cu" "*.Mask")
			(remove_unused_layers no)
			(net "GND")
			(clearance 0.1778)
			(thermal_gap 0.1778)
		)
		(pad "BB1" thru_hole circle
			(at -8.50011 -8.199882)
			(size 0.7366 0.7366)
			(drill 0.369824)
			(layers "*.Cu" "*.Mask")
			(remove_unused_layers no)
			(net "HOST6_RST_N_C")
			(clearance 0.1778)
			(thermal_gap 0.1778)
		)
		(pad "BB2" thru_hole circle
			(at -7.750048 -6.800088)
			(size 0.7366 0.7366)
			(drill 0.369824)
			(layers "*.Cu" "*.Mask")
			(remove_unused_layers no)
			(net "8644_SDA_R_6")
			(clearance 0.1778)
			(thermal_gap 0.1778)
		)
		(pad "BB3" thru_hole circle
			(at -6.999986 -7.500112)
			(size 0.7366 0.7366)
			(drill 0.369824)
			(layers "*.Cu" "*.Mask")
			(remove_unused_layers no)
			(net "GND")
			(clearance 0.1778)
			(thermal_gap 0.1778)
		)
		(pad "BB4" thru_hole circle
			(at -6.249924 -8.199882)
			(size 0.7366 0.7366)
			(drill 0.369824)
			(layers "*.Cu" "*.Mask")
			(remove_unused_layers no)
			(net "PCIE_RX_P5")
			(clearance 0.1778)
			(thermal_gap 0.1778)
		)
		(pad "BB5" thru_hole circle
			(at -5.500116 -6.800088)
			(size 0.7366 0.7366)
			(drill 0.369824)
			(layers "*.Cu" "*.Mask")
			(remove_unused_layers no)
			(net "PCIE_RX_N5")
			(clearance 0.1778)
			(thermal_gap 0.1778)
		)
		(pad "BB6" thru_hole circle
			(at -4.750054 -7.500112)
			(size 0.7366 0.7366)
			(drill 0.369824)
			(layers "*.Cu" "*.Mask")
			(remove_unused_layers no)
			(net "GND")
			(clearance 0.1778)
			(thermal_gap 0.1778)
		)
		(pad "BB7" thru_hole circle
			(at -3.999992 -8.199882)
			(size 0.7366 0.7366)
			(drill 0.369824)
			(layers "*.Cu" "*.Mask")
			(remove_unused_layers no)
			(net "PCIE_RX_P6")
			(clearance 0.1778)
			(thermal_gap 0.1778)
		)
		(pad "BB8" thru_hole circle
			(at -3.24993 -6.800088)
			(size 0.7366 0.7366)
			(drill 0.369824)
			(layers "*.Cu" "*.Mask")
			(remove_unused_layers no)
			(net "PCIE_RX_N6")
			(clearance 0.1778)
			(thermal_gap 0.1778)
		)
		(pad "BB9" thru_hole circle
			(at -2.500122 -7.500112)
			(size 0.7366 0.7366)
			(drill 0.369824)
			(layers "*.Cu" "*.Mask")
			(remove_unused_layers no)
			(net "GND")
			(clearance 0.1778)
			(thermal_gap 0.1778)
		)
		(pad "BC1" thru_hole circle
			(at -8.50011 -11.999976)
			(size 0.7366 0.7366)
			(drill 0.369824)
			(layers "*.Cu" "*.Mask")
			(remove_unused_layers no)
			(net "BMC_I2C12_MINI6_SCL")
			(clearance 0.1778)
			(thermal_gap 0.1778)
		)
		(pad "BC2" thru_hole circle
			(at -7.750048 -10.599928)
			(size 0.7366 0.7366)
			(drill 0.369824)
			(layers "*.Cu" "*.Mask")
			(remove_unused_layers no)
			(net "8644_CBL_PRSNT_R_6")
			(clearance 0.1778)
			(thermal_gap 0.1778)
		)
		(pad "BC3" thru_hole circle
			(at -6.999986 -11.299952)
			(size 0.7366 0.7366)
			(drill 0.369824)
			(layers "*.Cu" "*.Mask")
			(remove_unused_layers no)
			(net "GND")
			(clearance 0.1778)
			(thermal_gap 0.1778)
		)
		(pad "BC4" thru_hole circle
			(at -6.249924 -11.999976)
			(size 0.7366 0.7366)
			(drill 0.369824)
			(layers "*.Cu" "*.Mask")
			(remove_unused_layers no)
			(net "PCIE_TX_P4")
			(clearance 0.1778)
			(thermal_gap 0.1778)
		)
		(pad "BC5" thru_hole circle
			(at -5.500116 -10.599928)
			(size 0.7366 0.7366)
			(drill 0.369824)
			(layers "*.Cu" "*.Mask")
			(remove_unused_layers no)
			(net "PCIE_TX_N4")
			(clearance 0.1778)
			(thermal_gap 0.1778)
		)
		(pad "BC6" thru_hole circle
			(at -4.750054 -11.299952)
			(size 0.7366 0.7366)
			(drill 0.369824)
			(layers "*.Cu" "*.Mask")
			(remove_unused_layers no)
			(net "GND")
			(clearance 0.1778)
			(thermal_gap 0.1778)
		)
		(pad "BC7" thru_hole circle
			(at -3.999992 -11.999976)
			(size 0.7366 0.7366)
			(drill 0.369824)
			(layers "*.Cu" "*.Mask")
			(remove_unused_layers no)
			(net "PCIE_TX_P7")
			(clearance 0.1778)
			(thermal_gap 0.1778)
		)
		(pad "BC8" thru_hole circle
			(at -3.24993 -10.599928)
			(size 0.7366 0.7366)
			(drill 0.369824)
			(layers "*.Cu" "*.Mask")
			(remove_unused_layers no)
			(net "PCIE_TX_N7")
			(clearance 0.1778)
			(thermal_gap 0.1778)
		)
		(pad "BC9" thru_hole circle
			(at -2.500122 -11.299952)
			(size 0.7366 0.7366)
			(drill 0.369824)
			(layers "*.Cu" "*.Mask")
			(remove_unused_layers no)
			(net "GND")
			(clearance 0.1778)
			(thermal_gap 0.1778)
		)
		(pad "BD1" thru_hole circle
			(at -8.50011 -15.80007)
			(size 0.7366 0.7366)
			(drill 0.369824)
			(layers "*.Cu" "*.Mask")
			(remove_unused_layers no)
			(net "8644_USB_DN6")
			(clearance 0.1778)
			(thermal_gap 0.1778)
		)
		(pad "BD2" thru_hole circle
			(at -7.750048 -14.400022)
			(size 0.7366 0.7366)
			(drill 0.369824)
			(layers "*.Cu" "*.Mask")
			(remove_unused_layers no)
			(net "8644_USB_DP6")
			(clearance 0.1778)
			(thermal_gap 0.1778)
		)
		(pad "BD3" thru_hole circle
			(at -6.999986 -15.100046)
			(size 0.7366 0.7366)
			(drill 0.369824)
			(layers "*.Cu" "*.Mask")
			(remove_unused_layers no)
			(net "GND")
			(clearance 0.1778)
			(thermal_gap 0.1778)
		)
		(pad "BD4" thru_hole circle
			(at -6.249924 -15.80007)
			(size 0.7366 0.7366)
			(drill 0.369824)
			(layers "*.Cu" "*.Mask")
			(remove_unused_layers no)
			(net "PCIE_TX_P5")
			(clearance 0.1778)
			(thermal_gap 0.1778)
		)
		(pad "BD5" thru_hole circle
			(at -5.500116 -14.400022)
			(size 0.7366 0.7366)
			(drill 0.369824)
			(layers "*.Cu" "*.Mask")
			(remove_unused_layers no)
			(net "PCIE_TX_N5")
			(clearance 0.1778)
			(thermal_gap 0.1778)
		)
		(pad "BD6" thru_hole circle
			(at -4.750054 -15.100046)
			(size 0.7366 0.7366)
			(drill 0.369824)
			(layers "*.Cu" "*.Mask")
			(remove_unused_layers no)
			(net "GND")
			(clearance 0.1778)
			(thermal_gap 0.1778)
		)
		(pad "BD7" thru_hole circle
			(at -3.999992 -15.80007)
			(size 0.7366 0.7366)
			(drill 0.369824)
			(layers "*.Cu" "*.Mask")
			(remove_unused_layers no)
			(net "PCIE_TX_P6")
			(clearance 0.1778)
			(thermal_gap 0.1778)
		)
		(pad "BD8" thru_hole circle
			(at -3.24993 -14.400022)
			(size 0.7366 0.7366)
			(drill 0.369824)
			(layers "*.Cu" "*.Mask")
			(remove_unused_layers no)
			(net "PCIE_TX_N6")
			(clearance 0.1778)
			(thermal_gap 0.1778)
		)
		(pad "BD9" thru_hole circle
			(at -2.500122 -15.100046)
			(size 0.7366 0.7366)
			(drill 0.369824)
			(layers "*.Cu" "*.Mask")
			(remove_unused_layers no)
			(net "GND")
			(clearance 0.1778)
			(thermal_gap 0.1778)
		)
		(pad "CA1" thru_hole circle
			(at 2.500122 -4.400042)
			(size 0.7366 0.7366)
			(drill 0.369824)
			(layers "*.Cu" "*.Mask")
			(remove_unused_layers no)
			(net "PCIE_REFCLK_H1_P_R")
			(clearance 0.1778)
			(thermal_gap 0.1778)
		)
		(pad "CA2" thru_hole circle
			(at 3.24993 -2.999994)
			(size 0.7366 0.7366)
			(drill 0.369824)
			(layers "*.Cu" "*.Mask")
			(remove_unused_layers no)
			(net "PCIE_REFCLK_H1_N_R")
			(clearance 0.1778)
			(thermal_gap 0.1778)
		)
		(pad "CA3" thru_hole circle
			(at 3.999992 -3.700018)
			(size 0.7366 0.7366)
			(drill 0.369824)
			(layers "*.Cu" "*.Mask")
			(remove_unused_layers no)
			(net "GND")
			(clearance 0.1778)
			(thermal_gap 0.1778)
		)
		(pad "CA4" thru_hole circle
			(at 4.750054 -4.400042)
			(size 0.7366 0.7366)
			(drill 0.369824)
			(layers "*.Cu" "*.Mask")
			(remove_unused_layers no)
			(net "PCIE_RX_P8")
			(clearance 0.1778)
			(thermal_gap 0.1778)
		)
	)
)
